(kicad_pcb
	(version 20260206)
	(generator "pcbnew")
	(generator_version "10.0")
	(general
		(thickness 1.6)
		(legacy_teardrops no)
	)
	(paper "A4")
	(title_block
		(title "12092022_DA0F0TMDCD0_F0T_Management_Board_D_brd_V3_OCP.brd")
		(comment 1 "Grand Teton / footprints 805-809 of 1440")
	)
	(layers
		(0 "F.Cu" signal "TOP")
		(4 "In1.Cu" signal "GND")
		(6 "In2.Cu" signal "IN1")
		(8 "In3.Cu" signal "GND1")
		(10 "In4.Cu" signal "IN2")
		(12 "In5.Cu" signal "VCC")
		(14 "In6.Cu" signal "VCC1")
		(16 "In7.Cu" signal "IN3")
		(18 "In8.Cu" signal "GND2")
		(20 "In9.Cu" signal "IN4")
		(22 "In10.Cu" signal "GND3")
		(2 "B.Cu" signal "BOTTOM")
		(9 "F.Adhes" user "F.Adhesive")
		(11 "B.Adhes" user "B.Adhesive")
		(13 "F.Paste" user "Package Geometry/Pastemask Top")
		(15 "B.Paste" user "Package Geometry/Pastemask Bottom")
		(5 "F.SilkS" user "Ref Des/Silkscreen Top")
		(7 "B.SilkS" user "Ref Des/Silkscreen Bottom")
		(1 "F.Mask" user "Board Geometry/Soldermask Top")
		(3 "B.Mask" user "Board Geometry/Soldermask Bottom")
		(17 "Dwgs.User" user "User.Drawings")
		(19 "Cmts.User" user "User.Comments")
		(21 "Eco1.User" user "User.Eco1")
		(23 "Eco2.User" user "User.Eco2")
		(25 "Edge.Cuts" user "Board Geometry/Outline")
		(27 "Margin" user)
		(31 "F.CrtYd" user "Package Geometry/Place Bound Top")
		(29 "B.CrtYd" user "Package Geometry/Place Bound Bottom")
		(35 "F.Fab" user "Ref Des/Assembly Top")
		(33 "B.Fab" user "Ref Des/Assembly Bottom")
	)
	(footprint ""
		(layer "B.Cu")
		(at 54.675024 -71.820024)
		(property "Reference" "R779"
			(at 0 0 0)
			(layer "B.SilkS")
			(hide yes)
			(effects
				(font
					(size 1.27 1.27)
				)
				(justify mirror)
			)
		)
		(property "Value" ""
			(at 0 0 0)
			(layer "B.Fab")
			(effects
				(font
					(size 1.27 1.27)
				)
				(justify mirror)
			)
		)
		(duplicate_pad_numbers_are_jumpers no)
		(fp_line
			(start -0.7874 -0.4064)
			(end -0.7874 0.4064)
			(stroke
				(width 0.1524)
				(type default)
			)
			(layer "B.SilkS")
		)
		(fp_line
			(start -0.7874 0.4064)
			(end 0.7874 0.4064)
			(stroke
				(width 0.1524)
				(type default)
			)
			(layer "B.SilkS")
		)
		(fp_line
			(start 0.7874 -0.4064)
			(end -0.7874 -0.4064)
			(stroke
				(width 0.1524)
				(type default)
			)
			(layer "B.SilkS")
		)
		(fp_line
			(start 0.7874 0.4064)
			(end 0.7874 -0.4064)
			(stroke
				(width 0.1524)
				(type default)
			)
			(layer "B.SilkS")
		)
		(fp_line
			(start -0.67945 -0.3048)
			(end -0.67945 0.3048)
			(stroke
				(width 0.1)
				(type default)
			)
			(layer "B.Fab")
		)
		(fp_line
			(start -0.67945 0.3048)
			(end -0.120396 0.3048)
			(stroke
				(width 0.1)
				(type default)
			)
			(layer "B.Fab")
		)
		(fp_line
			(start -0.12065 -0.3048)
			(end -0.67945 -0.3048)
			(stroke
				(width 0.1)
				(type default)
			)
			(layer "B.Fab")
		)
		(fp_line
			(start -0.12065 -0.2794)
			(end -0.12065 -0.3048)
			(stroke
				(width 0.1)
				(type default)
			)
			(layer "B.Fab")
		)
		(fp_line
			(start -0.120396 0.2794)
			(end 0.12065 0.2794)
			(stroke
				(width 0.1)
				(type default)
			)
			(layer "B.Fab")
		)
		(fp_line
			(start -0.120396 0.3048)
			(end -0.120396 0.2794)
			(stroke
				(width 0.1)
				(type default)
			)
			(layer "B.Fab")
		)
		(fp_line
			(start 0.12065 -0.305054)
			(end 0.12065 -0.2794)
			(stroke
				(width 0.1)
				(type default)
			)
			(layer "B.Fab")
		)
		(fp_line
			(start 0.12065 -0.2794)
			(end -0.12065 -0.2794)
			(stroke
				(width 0.1)
				(type default)
			)
			(layer "B.Fab")
		)
		(fp_line
			(start 0.12065 0.2794)
			(end 0.12065 0.3048)
			(stroke
				(width 0.1)
				(type default)
			)
			(layer "B.Fab")
		)
		(fp_line
			(start 0.12065 0.3048)
			(end 0.67945 0.3048)
			(stroke
				(width 0.1)
				(type default)
			)
			(layer "B.Fab")
		)
		(fp_line
			(start 0.67945 -0.305054)
			(end 0.12065 -0.305054)
			(stroke
				(width 0.1)
				(type default)
			)
			(layer "B.Fab")
		)
		(fp_line
			(start 0.67945 0.3048)
			(end 0.67945 -0.305054)
			(stroke
				(width 0.1)
				(type default)
			)
			(layer "B.Fab")
		)
		(pad "1" smd circle
			(at 0.40005 0 180)
			(size 0 0)
			(layers "B.Cu" "B.Mask" "B.Paste")
			(net "P2V5_AUX")
		)
		(pad "2" smd circle
			(at -0.40005 0 180)
			(size 0 0)
			(layers "B.Cu" "B.Mask" "B.Paste")
			(net "ADCVREFEXT1")
		)
	)
	(footprint ""
		(layer "B.Cu")
		(at 51.816 -66.7004 90)
		(property "Reference" "R407"
			(at 0 0 90)
			(layer "B.SilkS")
			(hide yes)
			(effects
				(font
					(size 1.27 1.27)
				)
				(justify mirror)
			)
		)
		(property "Value" ""
			(at 0 0 90)
			(layer "B.Fab")
			(effects
				(font
					(size 1.27 1.27)
				)
				(justify mirror)
			)
		)
		(duplicate_pad_numbers_are_jumpers no)
		(fp_line
			(start 0.7874 -0.4064)
			(end -0.7874 -0.4064)
			(stroke
				(width 0.1524)
				(type default)
			)
			(layer "B.SilkS")
		)
		(fp_line
			(start -0.7874 -0.4064)
			(end -0.7874 0.4064)
			(stroke
				(width 0.1524)
				(type default)
			)
			(layer "B.SilkS")
		)
		(fp_line
			(start 0.7874 0.4064)
			(end 0.7874 -0.4064)
			(stroke
				(width 0.1524)
				(type default)
			)
			(layer "B.SilkS")
		)
		(fp_line
			(start -0.7874 0.4064)
			(end 0.7874 0.4064)
			(stroke
				(width 0.1524)
				(type default)
			)
			(layer "B.SilkS")
		)
		(fp_line
			(start 0.67945 -0.305054)
			(end 0.12065 -0.305054)
			(stroke
				(width 0.1)
				(type default)
			)
			(layer "B.Fab")
		)
		(fp_line
			(start 0.12065 -0.305054)
			(end 0.12065 -0.2794)
			(stroke
				(width 0.1)
				(type default)
			)
			(layer "B.Fab")
		)
		(fp_line
			(start -0.12065 -0.3048)
			(end -0.67945 -0.3048)
			(stroke
				(width 0.1)
				(type default)
			)
			(layer "B.Fab")
		)
		(fp_line
			(start -0.67945 -0.3048)
			(end -0.67945 0.3048)
			(stroke
				(width 0.1)
				(type default)
			)
			(layer "B.Fab")
		)
		(fp_line
			(start 0.12065 -0.2794)
			(end -0.12065 -0.2794)
			(stroke
				(width 0.1)
				(type default)
			)
			(layer "B.Fab")
		)
		(fp_line
			(start -0.12065 -0.2794)
			(end -0.12065 -0.3048)
			(stroke
				(width 0.1)
				(type default)
			)
			(layer "B.Fab")
		)
		(fp_line
			(start 0.12065 0.2794)
			(end 0.12065 0.3048)
			(stroke
				(width 0.1)
				(type default)
			)
			(layer "B.Fab")
		)
		(fp_line
			(start -0.120396 0.2794)
			(end 0.12065 0.2794)
			(stroke
				(width 0.1)
				(type default)
			)
			(layer "B.Fab")
		)
		(fp_line
			(start 0.67945 0.3048)
			(end 0.67945 -0.305054)
			(stroke
				(width 0.1)
				(type default)
			)
			(layer "B.Fab")
		)
		(fp_line
			(start 0.12065 0.3048)
			(end 0.67945 0.3048)
			(stroke
				(width 0.1)
				(type default)
			)
			(layer "B.Fab")
		)
		(fp_line
			(start -0.120396 0.3048)
			(end -0.120396 0.2794)
			(stroke
				(width 0.1)
				(type default)
			)
			(layer "B.Fab")
		)
		(fp_line
			(start -0.67945 0.3048)
			(end -0.120396 0.3048)
			(stroke
				(width 0.1)
				(type default)
			)
			(layer "B.Fab")
		)
		(pad "1" smd circle
			(at 0.40005 0 270)
			(size 0 0)
			(layers "B.Cu" "B.Mask" "B.Paste")
			(net "FM_BMC_SUSACK_R1_N")
		)
		(pad "2" smd circle
			(at -0.40005 0 270)
			(size 0 0)
			(layers "B.Cu" "B.Mask" "B.Paste")
			(net "FM_BMC_SUSACK_N")
		)
	)
	(footprint ""
		(layer "B.Cu")
		(at 15.113 -18.161 -90)
		(property "Reference" "C321"
			(at 0 0 90)
			(layer "B.SilkS")
			(hide yes)
			(effects
				(font
					(size 1.27 1.27)
				)
				(justify mirror)
			)
		)
		(property "Value" ""
			(at 0 0 90)
			(layer "B.Fab")
			(effects
				(font
					(size 1.27 1.27)
				)
				(justify mirror)
			)
		)
		(duplicate_pad_numbers_are_jumpers no)
		(fp_line
			(start -0.7874 0.4064)
			(end 0.7874 0.4064)
			(stroke
				(width 0.1524)
				(type default)
			)
			(layer "B.SilkS")
		)
		(fp_line
			(start 0.7874 0.4064)
			(end 0.7874 -0.4064)
			(stroke
				(width 0.1524)
				(type default)
			)
			(layer "B.SilkS")
		)
		(fp_line
			(start -0.7874 -0.4064)
			(end -0.7874 0.4064)
			(stroke
				(width 0.1524)
				(type default)
			)
			(layer "B.SilkS")
		)
		(fp_line
			(start 0.7874 -0.4064)
			(end -0.7874 -0.4064)
			(stroke
				(width 0.1524)
				(type default)
			)
			(layer "B.SilkS")
		)
		(fp_line
			(start -0.67945 0.3048)
			(end -0.120396 0.3048)
			(stroke
				(width 0.1)
				(type default)
			)
			(layer "B.Fab")
		)
		(fp_line
			(start -0.120396 0.3048)
			(end -0.120396 0.2794)
			(stroke
				(width 0.1)
				(type default)
			)
			(layer "B.Fab")
		)
		(fp_line
			(start 0.12065 0.3048)
			(end 0.67945 0.3048)
			(stroke
				(width 0.1)
				(type default)
			)
			(layer "B.Fab")
		)
		(fp_line
			(start 0.67945 0.3048)
			(end 0.67945 -0.305054)
			(stroke
				(width 0.1)
				(type default)
			)
			(layer "B.Fab")
		)
		(fp_line
			(start -0.120396 0.2794)
			(end 0.12065 0.2794)
			(stroke
				(width 0.1)
				(type default)
			)
			(layer "B.Fab")
		)
		(fp_line
			(start 0.12065 0.2794)
			(end 0.12065 0.3048)
			(stroke
				(width 0.1)
				(type default)
			)
			(layer "B.Fab")
		)
		(fp_line
			(start -0.12065 -0.2794)
			(end -0.12065 -0.3048)
			(stroke
				(width 0.1)
				(type default)
			)
			(layer "B.Fab")
		)
		(fp_line
			(start 0.12065 -0.2794)
			(end -0.12065 -0.2794)
			(stroke
				(width 0.1)
				(type default)
			)
			(layer "B.Fab")
		)
		(fp_line
			(start -0.67945 -0.3048)
			(end -0.67945 0.3048)
			(stroke
				(width 0.1)
				(type default)
			)
			(layer "B.Fab")
		)
		(fp_line
			(start -0.12065 -0.3048)
			(end -0.67945 -0.3048)
			(stroke
				(width 0.1)
				(type default)
			)
			(layer "B.Fab")
		)
		(fp_line
			(start 0.12065 -0.305054)
			(end 0.12065 -0.2794)
			(stroke
				(width 0.1)
				(type default)
			)
			(layer "B.Fab")
		)
		(fp_line
			(start 0.67945 -0.305054)
			(end 0.12065 -0.305054)
			(stroke
				(width 0.1)
				(type default)
			)
			(layer "B.Fab")
		)
		(pad "1" smd circle
			(at 0.40005 0 90)
			(size 0 0)
			(layers "B.Cu" "B.Mask" "B.Paste")
			(net "PWR_LED_P5V_AUX")
		)
		(pad "2" smd circle
			(at -0.40005 0 90)
			(size 0 0)
			(layers "B.Cu" "B.Mask" "B.Paste")
			(net "GND")
		)
	)
	(footprint ""
		(layer "B.Cu")
		(at 103.8225 -65.6336 -90)
		(property "Reference" "J20"
			(at 0.8636 -2.95783 270)
			(unlocked yes)
			(layer "B.SilkS")
			(effects
				(font
					(size 0.7874 0.5842)
					(thickness 0.1524)
				)
				(justify left mirror)
			)
		)
		(property "Value" ""
			(at 0 0 90)
			(layer "B.Fab")
			(effects
				(font
					(size 1.27 1.27)
				)
				(justify mirror)
			)
		)
		(duplicate_pad_numbers_are_jumpers no)
		(fp_line
			(start -1.2192 2.1082)
			(end 1.2192 2.1082)
			(stroke
				(width 0.1524)
				(type default)
			)
			(layer "B.SilkS")
		)
		(fp_line
			(start 1.2192 2.1082)
			(end 1.2192 -2.1082)
			(stroke
				(width 0.1524)
				(type default)
			)
			(layer "B.SilkS")
		)
		(fp_line
			(start -1.2192 0.450088)
			(end -1.2192 2.1082)
			(stroke
				(width 0.1524)
				(type default)
			)
			(layer "B.SilkS")
		)
		(fp_line
			(start -1.2192 -2.1082)
			(end -1.2192 -0.466344)
			(stroke
				(width 0.1524)
				(type default)
			)
			(layer "B.SilkS")
		)
		(fp_line
			(start 1.2192 -2.1082)
			(end -1.2192 -2.1082)
			(stroke
				(width 0.1524)
				(type default)
			)
			(layer "B.SilkS")
		)
		(pad "" np_thru_hole circle
			(at -3.4671 -1.27 180)
			(size 1.0414 1.0414)
			(drill 1.0414)
			(layers "*.Cu" "*.Mask")
			(clearance 0.381)
			(thermal_gap 0.381)
		)
		(pad "" np_thru_hole circle
			(at -3.4671 1.27 180)
			(size 1.0414 1.0414)
			(drill 1.0414)
			(layers "*.Cu" "*.Mask")
			(clearance 0.381)
			(thermal_gap 0.381)
		)
		(pad "" np_thru_hole circle
			(at 2.8829 -1.27 180)
			(size 1.0414 1.0414)
			(drill 1.0414)
			(layers "*.Cu" "*.Mask")
			(clearance 0.381)
			(thermal_gap 0.381)
		)
		(pad "" np_thru_hole circle
			(at 2.8829 1.27 180)
			(size 1.0414 1.0414)
			(drill 1.0414)
			(layers "*.Cu" "*.Mask")
			(clearance 0.381)
			(thermal_gap 0.381)
		)
		(pad "1" smd rect
			(at -0.8255 -0.249936 180)
			(size 0.3048 0.508)
			(layers "B.Cu" "B.Mask" "B.Paste")
			(net "85_5INCH_BOT_DP")
		)
		(pad "2" smd rect
			(at -0.8255 0.249936 180)
			(size 0.3048 0.508)
			(layers "B.Cu" "B.Mask" "B.Paste")
			(net "85_5INCH_BOT_DN")
		)
		(pad "3" smd circle
			(at 0 0 90)
			(size 0 0)
			(layers "B.Cu" "B.Mask" "B.Paste")
			(net "GND_P1")
		)
		(zone
			(layers "F.Cu" "B.Cu" "In1.Cu" "In2.Cu" "In3.Cu" "In4.Cu" "In5.Cu" "In6.Cu"
				"In7.Cu" "In8.Cu" "In9.Cu" "In10.Cu"
			)
			(hatch none 0.5)
			(connect_pads
				(clearance 0)
			)
			(min_thickness 0.25)
			(keepout
				(tracks not_allowed)
				(vias allowed)
				(pads allowed)
				(copperpour not_allowed)
				(footprints allowed)
			)
			(placement
				(enabled no)
				(sheetname "")
			)
			(fill
				(thermal_gap 0.5)
				(thermal_bridge_width 0.5)
				(island_removal_mode 0)
			)
			(polygon
				(pts
					(arc
						(start 103.4796 -69.1007)
						(mid 101.6254 -69.1007)
						(end 103.4796 -69.1007)
					)
				)
			)
		)
		(zone
			(layers "F.Cu" "B.Cu" "In1.Cu" "In2.Cu" "In3.Cu" "In4.Cu" "In5.Cu" "In6.Cu"
				"In7.Cu" "In8.Cu" "In9.Cu" "In10.Cu"
			)
			(hatch none 0.5)
			(connect_pads
				(clearance 0)
			)
			(min_thickness 0.25)
			(keepout
				(tracks not_allowed)
				(vias allowed)
				(pads allowed)
				(copperpour not_allowed)
				(footprints allowed)
			)
			(placement
				(enabled no)
				(sheetname "")
			)
			(fill
				(thermal_gap 0.5)
				(thermal_bridge_width 0.5)
				(island_removal_mode 0)
			)
			(polygon
				(pts
					(arc
						(start 103.4796 -62.7507)
						(mid 101.6254 -62.7507)
						(end 103.4796 -62.7507)
					)
				)
			)
		)
		(zone
			(layers "F.Cu" "B.Cu" "In1.Cu" "In2.Cu" "In3.Cu" "In4.Cu" "In5.Cu" "In6.Cu"
				"In7.Cu" "In8.Cu" "In9.Cu" "In10.Cu"
			)
			(hatch none 0.5)
			(connect_pads
				(clearance 0)
			)
			(min_thickness 0.25)
			(keepout
				(tracks not_allowed)
				(vias allowed)
				(pads allowed)
				(copperpour not_allowed)
				(footprints allowed)
			)
			(placement
				(enabled no)
				(sheetname "")
			)
			(fill
				(thermal_gap 0.5)
				(thermal_bridge_width 0.5)
				(island_removal_mode 0)
			)
			(polygon
				(pts
					(arc
						(start 106.0196 -69.1007)
						(mid 104.1654 -69.1007)
						(end 106.0196 -69.1007)
					)
				)
			)
		)
		(zone
			(layers "F.Cu" "B.Cu" "In1.Cu" "In2.Cu" "In3.Cu" "In4.Cu" "In5.Cu" "In6.Cu"
				"In7.Cu" "In8.Cu" "In9.Cu" "In10.Cu"
			)
			(hatch none 0.5)
			(connect_pads
				(clearance 0)
			)
			(min_thickness 0.25)
			(keepout
				(tracks not_allowed)
				(vias allowed)
				(pads allowed)
				(copperpour not_allowed)
				(footprints allowed)
			)
			(placement
				(enabled no)
				(sheetname "")
			)
			(fill
				(thermal_gap 0.5)
				(thermal_bridge_width 0.5)
				(island_removal_mode 0)
			)
			(polygon
				(pts
					(arc
						(start 106.0196 -62.7507)
						(mid 104.1654 -62.7507)
						(end 106.0196 -62.7507)
					)
				)
			)
		)
		(zone
			(layer "B.Cu")
			(hatch none 0.5)
			(connect_pads
				(clearance 0)
			)
			(min_thickness 0.25)
			(keepout
				(tracks not_allowed)
				(vias allowed)
				(pads allowed)
				(copperpour not_allowed)
				(footprints allowed)
			)
			(placement
				(enabled no)
				(sheetname "")
			)
			(fill
				(thermal_gap 0.5)
				(thermal_bridge_width 0.5)
				(island_removal_mode 0)
			)
			(polygon
				(pts
					(xy 104.37114 -66.7512) (xy 104.275636 -66.7512) (xy 104.275636 -66.1543) (xy 103.869236 -66.1543)
					(xy 103.869236 -66.7512) (xy 103.775764 -66.7512) (xy 103.775764 -66.1543) (xy 103.369364 -66.1543)
					(xy 103.369364 -66.7512) (xy 103.27386 -66.7512) (xy 103.27386 -66.0527) (xy 104.37114 -66.0527)
				)
			)
		)
	)
	(footprint ""
		(layer "B.Cu")
		(at 14.2494 -83.693 90)
		(property "Reference" "R808"
			(at 0 0 90)
			(layer "B.SilkS")
			(hide yes)
			(effects
				(font
					(size 1.27 1.27)
				)
				(justify mirror)
			)
		)
		(property "Value" ""
			(at 0 0 90)
			(layer "B.Fab")
			(effects
				(font
					(size 1.27 1.27)
				)
				(justify mirror)
			)
		)
		(duplicate_pad_numbers_are_jumpers no)
		(fp_line
			(start 0.7874 -0.4064)
			(end -0.7874 -0.4064)
			(stroke
				(width 0.1524)
				(type default)
			)
			(layer "B.SilkS")
		)
		(fp_line
			(start -0.7874 -0.4064)
			(end -0.7874 0.4064)
			(stroke
				(width 0.1524)
				(type default)
			)
			(layer "B.SilkS")
		)
		(fp_line
			(start 0.7874 0.4064)
			(end 0.7874 -0.4064)
			(stroke
				(width 0.1524)
				(type default)
			)
			(layer "B.SilkS")
		)
		(fp_line
			(start -0.7874 0.4064)
			(end 0.7874 0.4064)
			(stroke
				(width 0.1524)
				(type default)
			)
			(layer "B.SilkS")
		)
		(fp_line
			(start 0.67945 -0.305054)
			(end 0.12065 -0.305054)
			(stroke
				(width 0.1)
				(type default)
			)
			(layer "B.Fab")
		)
		(fp_line
			(start 0.12065 -0.305054)
			(end 0.12065 -0.2794)
			(stroke
				(width 0.1)
				(type default)
			)
			(layer "B.Fab")
		)
		(fp_line
			(start -0.12065 -0.3048)
			(end -0.67945 -0.3048)
			(stroke
				(width 0.1)
				(type default)
			)
			(layer "B.Fab")
		)
		(fp_line
			(start -0.67945 -0.3048)
			(end -0.67945 0.3048)
			(stroke
				(width 0.1)
				(type default)
			)
			(layer "B.Fab")
		)
		(fp_line
			(start 0.12065 -0.2794)
			(end -0.12065 -0.2794)
			(stroke
				(width 0.1)
				(type default)
			)
			(layer "B.Fab")
		)
		(fp_line
			(start -0.12065 -0.2794)
			(end -0.12065 -0.3048)
			(stroke
				(width 0.1)
				(type default)
			)
			(layer "B.Fab")
		)
		(fp_line
			(start 0.12065 0.2794)
			(end 0.12065 0.3048)
			(stroke
				(width 0.1)
				(type default)
			)
			(layer "B.Fab")
		)
		(fp_line
			(start -0.120396 0.2794)
			(end 0.12065 0.2794)
			(stroke
				(width 0.1)
				(type default)
			)
			(layer "B.Fab")
		)
		(fp_line
			(start 0.67945 0.3048)
			(end 0.67945 -0.305054)
			(stroke
				(width 0.1)
				(type default)
			)
			(layer "B.Fab")
		)
		(fp_line
			(start 0.12065 0.3048)
			(end 0.67945 0.3048)
			(stroke
				(width 0.1)
				(type default)
			)
			(layer "B.Fab")
		)
		(fp_line
			(start -0.120396 0.3048)
			(end -0.120396 0.2794)
			(stroke
				(width 0.1)
				(type default)
			)
			(layer "B.Fab")
		)
		(fp_line
			(start -0.67945 0.3048)
			(end -0.120396 0.3048)
			(stroke
				(width 0.1)
				(type default)
			)
			(layer "B.Fab")
		)
		(pad "1" smd circle
			(at 0.40005 0 270)
			(size 0 0)
			(layers "B.Cu" "B.Mask" "B.Paste")
			(net "PU_FPGA_CONFIG_DONE")
		)
		(pad "2" smd circle
			(at -0.40005 0 270)
			(size 0 0)
			(layers "B.Cu" "B.Mask" "B.Paste")
			(net "PVCCIO_AUX_PLD")
		)
	)
)
